# T6G (Grand Teton) — schematic netlist excerpt (pin names and nets, part order shuffled) for the footprints in the layout excerpt that follows; sources: Cadence DE-HDL packaged netlist, KiCad conversion of 04192023_DAF0TMB3IC0_F0TG_MB_C_brd_V02_OCP.brd

U52  ISL28022FRZT  ISL28022FRZ-T IC  pkg QFN16_TH_0-5_3X3XH  page 357
  A1  = INA230_8_A1
  A0  = INA230_8_A0
  \ext_clk||int\  = P12V_E1S_0_ADC_ALERT_R
  \sda||smbdat\  = SMB_INA230_8_3V3AUX_SDA_R1
  \scl|||smbclk\  = SMB_INA230_8_3V3AUX_SCL_R1
  NC0  = NC_INA230_8_NC0
  NC1  = NC_INA230_8_NC1
  NC2  = NC_INA230_8_NC2
  VCC  = P3V3_AUX
  GND  = GND
  VBUS  = P12V_E1S_0
  VINM  = VSENSE_P12V_INA230_8_INN
  VINP  = VSENSE_P12V_INA230_8_INP
  NC3  = NC_INA230_8_NC3
  NC4  = NC_INA230_8_NC4
  NC5  = NC_INA230_8_NC5
  TH_GND  = GND

(kicad_pcb
	(version 20260206)
	(generator "pcbnew")
	(generator_version "10.0")
	(general
		(thickness 1.6)
		(legacy_teardrops no)
	)
	(paper "A4")
	(title_block
		(title "04192023_DAF0TMB3IC0_F0TG_MB_C_brd_V02_OCP.brd")
		(comment 1 "Grand Teton / footprints 4330-4330 of 8354")
	)
	(layers
		(0 "F.Cu" signal "TOP")
		(4 "In1.Cu" signal "GND")
		(6 "In2.Cu" signal "IN1")
		(8 "In3.Cu" signal "GND1")
		(10 "In4.Cu" signal "IN2")
		(12 "In5.Cu" signal "GND2")
		(14 "In6.Cu" signal "IN3")
		(16 "In7.Cu" signal "GND3")
		(18 "In8.Cu" signal "VCC")
		(20 "In9.Cu" signal "VCC1")
		(22 "In10.Cu" signal "GND4")
		(24 "In11.Cu" signal "IN4")
		(26 "In12.Cu" signal "GND5")
		(28 "In13.Cu" signal "IN5")
		(30 "In14.Cu" signal "GND6")
		(32 "In15.Cu" signal "IN6")
		(34 "In16.Cu" signal "GND7")
		(2 "B.Cu" signal "BOTTOM")
		(9 "F.Adhes" user "F.Adhesive")
		(11 "B.Adhes" user "B.Adhesive")
		(13 "F.Paste" user "Package Geometry/Pastemask Top")
		(15 "B.Paste" user "Package Geometry/Pastemask Bottom")
		(5 "F.SilkS" user "Ref Des/Silkscreen Top")
		(7 "B.SilkS" user "Ref Des/Silkscreen Bottom")
		(1 "F.Mask" user "Board Geometry/Soldermask Top")
		(3 "B.Mask" user "Board Geometry/Soldermask Bottom")
		(17 "Dwgs.User" user "User.Drawings")
		(19 "Cmts.User" user "User.Comments")
		(21 "Eco1.User" user "User.Eco1")
		(23 "Eco2.User" user "User.Eco2")
		(25 "Edge.Cuts" user "Board Geometry/Outline")
		(27 "Margin" user)
		(31 "F.CrtYd" user "Package Geometry/Place Bound Top")
		(29 "B.CrtYd" user "Package Geometry/Place Bound Bottom")
		(35 "F.Fab" user "Ref Des/Assembly Top")
		(33 "B.Fab" user "Ref Des/Assembly Bottom")
	)
	(footprint ""
		(layer "F.Cu")
		(at 325.095108 -103.30815)
		(property "Reference" "U52"
			(at -1.63449 -4.200144 0)
			(unlocked yes)
			(layer "F.SilkS")
			(effects
				(font
					(size 0.7874 0.5842)
					(thickness 0.1524)
				)
			)
		)
		(property "Value" ""
			(at 0 0 0)
			(layer "F.Fab")
			(effects
				(font
					(size 1.27 1.27)
				)
			)
		)
		(duplicate_pad_numbers_are_jumpers no)
		(fp_line
			(start -1.500124 -1.500124)
			(end -1.004062 -1.500124)
			(stroke
				(width 0.1524)
				(type default)
			)
			(layer "F.SilkS")
		)
		(fp_line
			(start -1.500124 -1.004062)
			(end -1.500124 -1.500124)
			(stroke
				(width 0.1524)
				(type default)
			)
			(layer "F.SilkS")
		)
		(fp_line
			(start -1.500124 1.500124)
			(end -1.500124 1.004062)
			(stroke
				(width 0.1524)
				(type default)
			)
			(layer "F.SilkS")
		)
		(fp_line
			(start -1.004062 1.500124)
			(end -1.500124 1.500124)
			(stroke
				(width 0.1524)
				(type default)
			)
			(layer "F.SilkS")
		)
		(fp_line
			(start 1.004062 -1.500124)
			(end 1.500124 -1.500124)
			(stroke
				(width 0.1524)
				(type default)
			)
			(layer "F.SilkS")
		)
		(fp_line
			(start 1.500124 -1.500124)
			(end 1.500124 -1.004062)
			(stroke
				(width 0.1524)
				(type default)
			)
			(layer "F.SilkS")
		)
		(fp_line
			(start 1.500124 1.004062)
			(end 1.500124 1.500124)
			(stroke
				(width 0.1524)
				(type default)
			)
			(layer "F.SilkS")
		)
		(fp_line
			(start 1.500124 1.500124)
			(end 1.004062 1.500124)
			(stroke
				(width 0.1524)
				(type default)
			)
			(layer "F.SilkS")
		)
		(fp_poly
			(pts
				(xy -2.413 -2.50698) (xy -3.089402 -1.74879) (xy -1.992884 -1.45161)
			)
			(stroke
				(width 0)
				(type default)
			)
			(fill yes)
			(layer "F.SilkS")
		)
		(fp_line
			(start -1.500124 -1.500124)
			(end 1.500124 -1.500124)
			(stroke
				(width 0.1)
				(type default)
			)
			(layer "F.Fab")
		)
		(fp_line
			(start -1.500124 1.500124)
			(end -1.500124 -1.500124)
			(stroke
				(width 0.1)
				(type default)
			)
			(layer "F.Fab")
		)
		(fp_line
			(start 1.500124 -1.500124)
			(end 1.500124 1.500124)
			(stroke
				(width 0.1)
				(type default)
			)
			(layer "F.Fab")
		)
		(fp_line
			(start 1.500124 1.500124)
			(end -1.500124 1.500124)
			(stroke
				(width 0.1)
				(type default)
			)
			(layer "F.Fab")
		)
		(fp_poly
			(pts
				(xy -2.847848 -1.258062) (xy -2.847848 -0.242062) (xy -1.831848 -0.750062)
			)
			(stroke
				(width 0)
				(type default)
			)
			(fill yes)
			(layer "F.Fab")
		)
		(pad "1" smd rect
			(at -1.400048 -0.750062 270)
			(size 0.2286 0.6096)
			(layers "F.Cu" "F.Mask" "F.Paste")
			(net "INA230_8_A1")
		)
		(pad "2" smd rect
			(at -1.400048 -0.249936 270)
			(size 0.2286 0.6096)
			(layers "F.Cu" "F.Mask" "F.Paste")
			(net "INA230_8_A0")
		)
		(pad "3" smd rect
			(at -1.400048 0.249936 270)
			(size 0.2286 0.6096)
			(layers "F.Cu" "F.Mask" "F.Paste")
			(net "P12V_E1S_0_ADC_ALERT_R")
		)
		(pad "4" smd rect
			(at -1.400048 0.750062 270)
			(size 0.2286 0.6096)
			(layers "F.Cu" "F.Mask" "F.Paste")
			(net "SMB_INA230_8_3V3AUX_SDA_R1")
		)
		(pad "5" smd rect
			(at -0.750062 1.400048)
			(size 0.2286 0.6096)
			(layers "F.Cu" "F.Mask" "F.Paste")
			(net "SMB_INA230_8_3V3AUX_SCL_R1")
		)
		(pad "6" smd rect
			(at -0.249936 1.400048)
			(size 0.2286 0.6096)
			(layers "F.Cu" "F.Mask" "F.Paste")
			(net "NC_INA230_8_NC0")
		)
		(pad "7" smd rect
			(at 0.249936 1.400048)
			(size 0.2286 0.6096)
			(layers "F.Cu" "F.Mask" "F.Paste")
			(net "NC_INA230_8_NC1")
		)
		(pad "8" smd rect
			(at 0.750062 1.400048)
			(size 0.2286 0.6096)
			(layers "F.Cu" "F.Mask" "F.Paste")
			(net "NC_INA230_8_NC2")
		)
		(pad "9" smd rect
			(at 1.400048 0.750062 270)
			(size 0.2286 0.6096)
			(layers "F.Cu" "F.Mask" "F.Paste")
			(net "P3V3_AUX")
		)
		(pad "10" smd rect
			(at 1.400048 0.249936 270)
			(size 0.2286 0.6096)
			(layers "F.Cu" "F.Mask" "F.Paste")
			(net "GND")
		)
		(pad "11" smd rect
			(at 1.400048 -0.249936 270)
			(size 0.2286 0.6096)
			(layers "F.Cu" "F.Mask" "F.Paste")
			(net "P12V_E1S_0")
		)
		(pad "12" smd rect
			(at 1.400048 -0.750062 270)
			(size 0.2286 0.6096)
			(layers "F.Cu" "F.Mask" "F.Paste")
			(net "VSENSE_P12V_INA230_8_INN")
		)
		(pad "13" smd rect
			(at 0.750062 -1.400048)
			(size 0.2286 0.6096)
			(layers "F.Cu" "F.Mask" "F.Paste")
			(net "VSENSE_P12V_INA230_8_INP")
		)
		(pad "14" smd rect
			(at 0.249936 -1.400048)
			(size 0.2286 0.6096)
			(layers "F.Cu" "F.Mask" "F.Paste")
			(net "NC_INA230_8_NC3")
		)
		(pad "15" smd rect
			(at -0.249936 -1.400048)
			(size 0.2286 0.6096)
			(layers "F.Cu" "F.Mask" "F.Paste")
			(net "NC_INA230_8_NC4")
		)
		(pad "16" smd rect
			(at -0.750062 -1.400048)
			(size 0.2286 0.6096)
			(layers "F.Cu" "F.Mask" "F.Paste")
			(net "NC_INA230_8_NC5")
		)
		(pad "TH" smd rect
			(at 0 0)
			(size 1.7018 1.7018)
			(layers "F.Cu" "F.Mask" "F.Paste")
			(net "GND")
		)
		(zone
			(layer "F.Cu")
			(hatch none 0.5)
			(connect_pads
				(clearance 0)
			)
			(min_thickness 0.25)
			(keepout
				(tracks not_allowed)
				(vias allowed)
				(pads allowed)
				(copperpour not_allowed)
				(footprints allowed)
			)
			(placement
				(enabled no)
				(sheetname "")
			)
			(fill
				(thermal_gap 0.5)
				(thermal_bridge_width 0.5)
				(island_removal_mode 0)
			)
			(polygon
				(pts
					(xy 324.05066 -103.33355) (xy 324.05066 -104.352598) (xy 326.139556 -104.352598) (xy 326.139556 -102.263702)
					(xy 324.05066 -102.263702) (xy 324.05066 -103.30815) (xy 324.193408 -103.30815) (xy 324.193408 -102.40645)
					(xy 325.996808 -102.40645) (xy 325.996808 -104.20985) (xy 324.193408 -104.20985) (xy 324.193408 -103.33355)
				)
			)
		)
	)
)
